FILE_TYPE = CONNECTIVITY;
{Allegro Design Entry HDL 17.2-2016 S081 (4005846) 1/11/2022}
"PAGE_NUMBER" = 148;
0"NC";
1"GND\g";
2"GND\g";
3"P5E_CPU1_PE4_RX_DP<8>";
4"P5E_CPU1_PE0_TX_C_DN<2>";
5"P5E_CPU1_PE4_RX_DN<13>";
6"P5E_CPU1_PE0_RX_DP<2>";
7"P5E_CPU1_PE0_RX_DN<2>";
8"P5E_CPU1_PE4_TX_C_DP<15>";
9"P5E_CPU1_PE0_TX_C_DP<0>";
10"P5E_CPU1_PE0_TX_C_DP<1>";
11"P5E_CPU1_PE4_RX_DP<14>";
12"P5E_CPU1_PE4_RX_DN<14>";
13"P5E_CPU1_PE0_RX_DN<1>";
14"P5E_CPU1_PE4_RX_DP<10>";
15"P5E_CPU1_PE4_RX_DN<10>";
16"P5E_CPU1_PE4_RX_DP<11>";
17"P5E_CPU1_PE4_RX_DN<11>";
18"P5E_CPU1_PE0_TX_C_DN<4>";
19"P5E_CPU1_PE0_TX_C_DP<4>";
20"P5E_CPU1_PE4_TX_C_DN<11>";
21"P5E_CPU1_PE4_TX_C_DP<11>";
22"FM_GPU_PWR_EN_R_BUF";
23"GPU_BASE_ID0";
24"P5E_CPU1_PE0_RX_DN<5>";
25"P5E_CPU1_PE0_RX_DP<5>";
26"P5E_CPU1_PE0_TX_C_DN<5>";
27"P5E_CPU1_PE0_TX_C_DP<5>";
28"P5E_CPU1_PE4_TX_C_DN<10>";
29"P5E_CPU1_PE4_TX_C_DP<10>";
30"P5E_CPU1_PE0_RX_DN<6>";
31"P5E_CPU1_PE0_RX_DP<6>";
32"P5E_CPU1_PE4_RX_DP<9>";
33"P5E_CPU1_PE4_RX_DN<9>";
34"P5E_CPU1_PE0_TX_C_DN<6>";
35"P5E_CPU1_PE0_RX_DP<7>";
36"P5E_CPU1_PE4_RX_DN<8>";
37"P5E_CPU1_PE0_RX_DN<7>";
38"GPU_PEX_STRAP1";
39"GPU_PRSNT_N";
40"P5E_CPU1_PE4_TX_C_DP<9>";
41"P5E_CPU1_PE4_TX_C_DN<9>";
42"P5E_CPU1_PE0_RX_DP<1>";
43"GPU_FPGA_RST_R_BUF_N";
44"GPU_BASE_ID1";
45"P5E_CPU1_PE4_TX_C_DN<15>";
46"P5E_CPU1_PE0_TX_C_DN<0>";
47"P5E_CPU1_PE4_RX_DN<15>";
48"P5E_CPU1_PE0_RX_DP<4>";
49"P5E_CPU1_PE0_TX_C_DP<6>";
50"P5E_CPU1_PE0_TX_C_DN<1>";
51"P5E_CPU1_PE4_TX_C_DN<14>";
52"P5E_CPU1_PE4_TX_C_DP<14>";
53"P5E_CPU1_PE0_RX_DN<0>";
54"P5E_CPU1_PE0_RX_DP<0>";
55"P5E_CPU1_PE0_RX_DP<3>";
56"P5E_CPU1_PE4_TX_C_DP<13>";
57"P5E_CPU1_PE4_TX_C_DN<13>";
58"P5E_CPU1_PE0_TX_C_DP<2>";
59"P5E_CPU1_PE4_RX_DP<13>";
60"P5E_CPU1_PE4_RX_DP<15>";
61"FM_GPU_PWRGD";
62"GPU_PEX_STRAP0";
63"P5E_CPU1_PE0_RX_DN<3>";
64"P5E_CPU1_PE4_RX_DN<12>";
65"P5E_CPU1_PE0_TX_C_DP<3>";
66"P5E_CPU1_PE4_RX_DP<12>";
67"P5E_CPU1_PE0_TX_C_DP<7>";
68"P5E_CPU1_PE0_TX_C_DN<7>";
69"P5E_CPU1_PE4_TX_C_DN<8>";
70"P5E_CPU1_PE4_TX_C_DP<8>";
71"P5E_CPU1_PE0_RX_DN<4>";
72"P5E_CPU1_PE0_TX_C_DN<3>";
73"P5E_CPU1_PE4_TX_C_DN<12>";
74"P5E_CPU1_PE4_TX_C_DP<12>";
%"CONN112_10137002101LF"
"1","(-25,1775)","0","pure_quanta","I74";
;
PART_NUMBER"DFHSB2FR012"
PART_TYPE"THLF"
MATERIAL"IO"
LOCATION"J111"
CDS_LIB"pure_quanta"
NEEDS_NO_SIZE"TRUE"
CDS_LMAN_SYM_OUTLINE"-775,1650,775,-1650"
VALUE"CONN112_10137002-101LF"
$SEC"1"
CDS_SEC"1";
"N8"
$PN"N8"44;
"M8"
$PN"M8"1;
"N7"
$PN"N7"1;
"M7"
$PN"M7"52;
"N6"
$PN"N6"61;
"M6"
$PN"M6"1;
"N5"
$PN"N5"1;
"M5"
$PN"M5"74;
"L5"
$PN"L5"73;
"L6"
$PN"L6"56;
"L7"
$PN"L7"51;
"L8"
$PN"L8"8;
"K5"
$PN"K5"1;
"K6"
$PN"K6"57;
"K7"
$PN"K7"1;
"K8"
$PN"K8"45;
"J5"
$PN"J5"65;
"J6"
$PN"J6"1;
"J7"
$PN"J7"10;
"J8"
$PN"J8"1;
"I5"
$PN"I5"72;
"I6"
$PN"I6"58;
"I7"
$PN"I7"50;
"I8"
$PN"I8"9;
"H5"
$PN"H5"1;
"H6"
$PN"H6"4;
"H7"
$PN"H7"1;
"H8"
$PN"H8"46;
"G5"
$PN"G5"66;
"G6"
$PN"G6"1;
"G7"
$PN"G7"11;
"G8"
$PN"G8"1;
"F5"
$PN"F5"64;
"F6"
$PN"F6"5;
"F7"
$PN"F7"12;
"F8"
$PN"F8"47;
"E5"
$PN"E5"1;
"E6"
$PN"E6"59;
"E7"
$PN"E7"1;
"E8"
$PN"E8"60;
"D5"
$PN"D5"63;
"D6"
$PN"D6"1;
"D7"
$PN"D7"13;
"D8"
$PN"D8"1;
"C5"
$PN"C5"55;
"C6"
$PN"C6"6;
"C7"
$PN"C7"42;
"C8"
$PN"C8"54;
"B5"
$PN"B5"1;
"B6"
$PN"B6"7;
"B7"
$PN"B7"1;
"B8"
$PN"B8"53;
"A5"
$PN"A5"62;
"A6"
$PN"A6"1;
"A7"
$PN"A7"43;
"A8"
$PN"A8"1;
%"CONN112_10137002101LF"
"2","(4725,1775)","0","pure_quanta","I75";
;
PART_NUMBER"DFHSB2FR012"
PART_TYPE"THLF"
MATERIAL"IO"
LOCATION"J111"
VALUE"CONN112_10137002-101LF"
CDS_LIB"pure_quanta"
NEEDS_NO_SIZE"TRUE"
CDS_LMAN_SYM_OUTLINE"-775,1650,775,-1650"
$SEC"2"
CDS_SEC"2";
"N4"
$PN"N4"22;
"M4"
$PN"M4"2;
"N3"
$PN"N3"2;
"M3"
$PN"M3"29;
"N2"
$PN"N2"39;
"M2"
$PN"M2"2;
"N1"
$PN"N1"2;
"M1"
$PN"M1"70;
"L1"
$PN"L1"69;
"L2"
$PN"L2"40;
"L3"
$PN"L3"28;
"L4"
$PN"L4"20;
"K1"
$PN"K1"2;
"K2"
$PN"K2"41;
"K3"
$PN"K3"2;
"K4"
$PN"K4"21;
"J1"
$PN"J1"67;
"J2"
$PN"J2"2;
"J3"
$PN"J3"27;
"J4"
$PN"J4"2;
"I1"
$PN"I1"68;
"I2"
$PN"I2"49;
"I3"
$PN"I3"26;
"I4"
$PN"I4"19;
"H1"
$PN"H1"2;
"H2"
$PN"H2"34;
"H3"
$PN"H3"2;
"H4"
$PN"H4"18;
"G1"
$PN"G1"3;
"G2"
$PN"G2"2;
"G3"
$PN"G3"14;
"G4"
$PN"G4"2;
"F1"
$PN"F1"36;
"F2"
$PN"F2"33;
"F3"
$PN"F3"15;
"F4"
$PN"F4"17;
"E1"
$PN"E1"2;
"E2"
$PN"E2"32;
"E3"
$PN"E3"2;
"E4"
$PN"E4"16;
"D1"
$PN"D1"35;
"D2"
$PN"D2"2;
"D3"
$PN"D3"25;
"D4"
$PN"D4"2;
"C1"
$PN"C1"37;
"C2"
$PN"C2"31;
"C3"
$PN"C3"24;
"C4"
$PN"C4"48;
"B1"
$PN"B1"2;
"B2"
$PN"B2"30;
"B3"
$PN"B3"2;
"B4"
$PN"B4"71;
"A1"
$PN"A1"38;
"A2"
$PN"A2"2;
"A3"
$PN"A3"23;
"A4"
$PN"A4"2;
%"UNIVERSAL_GND"
"1","(3575,-175)","0","logical_power","I92";
;
HDL_POWER"GND"
CDS_LIB"logical_power";
"A"2;
%"UNIVERSAL_GND"
"1","(-1125,-125)","0","logical_power","I93";
;
CDS_LIB"logical_power"
HDL_POWER"GND";
"A"1;
END.
